(kicad_pcb
	(version 20260206)
	(generator "pcbnew")
	(generator_version "10.0")
	(general
		(thickness 1.6)
		(legacy_teardrops no)
	)
	(paper "A4")
	(title_block
		(title "timecard-production-celestica-r4006 — R4006-B0001-02_R01.brd")
		(comment 1 "Time Appliance Project (Time Card) / footprints 273-277 of 1113")
	)
	(layers
		(0 "F.Cu" signal "TOP")
		(4 "In1.Cu" signal "L02_GND1")
		(6 "In2.Cu" signal "L03_SIG1")
		(8 "In3.Cu" signal "L04_GND2")
		(10 "In4.Cu" signal "L05_VCC1")
		(12 "In5.Cu" signal "L06_VCC2")
		(14 "In6.Cu" signal "L07_GND3")
		(16 "In7.Cu" signal "L08_SIG2")
		(18 "In8.Cu" signal "L09_GND4")
		(2 "B.Cu" signal "BOTTOM")
		(9 "F.Adhes" user "F.Adhesive")
		(11 "B.Adhes" user "B.Adhesive")
		(13 "F.Paste" user "Package Geometry/Pastemask Top")
		(15 "B.Paste" user "Package Geometry/Pastemask Bottom")
		(5 "F.SilkS" user "Ref Des/Silkscreen Top")
		(7 "B.SilkS" user "Ref Des/Silkscreen Bottom")
		(1 "F.Mask" user "Board Geometry/Soldermask Top")
		(3 "B.Mask" user "Board Geometry/Soldermask Bottom")
		(17 "Dwgs.User" user "User.Drawings")
		(19 "Cmts.User" user "User.Comments")
		(21 "Eco1.User" user "User.Eco1")
		(23 "Eco2.User" user "User.Eco2")
		(25 "Edge.Cuts" user "Board Geometry/Outline")
		(27 "Margin" user)
		(31 "F.CrtYd" user "Package Geometry/Place Bound Top")
		(29 "B.CrtYd" user "Package Geometry/Place Bound Bottom")
		(35 "F.Fab" user "Ref Des/Assembly Top")
		(33 "B.Fab" user "Ref Des/Assembly Bottom")
	)
	(footprint ""
		(layer "F.Cu")
		(at 156.04998 -107.849924 -90)
		(property "Reference" "DS11"
			(at -0.100076 -2.23139 90)
			(unlocked yes)
			(layer "F.SilkS")
			(effects
				(font
					(size 0.7874 0.5842)
					(thickness 0.1524)
				)
			)
		)
		(property "Value" ""
			(at 0 0 270)
			(layer "F.Fab")
			(effects
				(font
					(size 1.27 1.27)
				)
			)
		)
		(property "Device Type" "OPTICAL-G170-10143-01"
			(at 0.1778 1.483081 270)
			(unlocked yes)
			(layer "F.Fab")
			(hide yes)
			(effects
				(font
					(size 0.786892 0.583946)
					(thickness 0.000001)
				)
			)
		)
		(property "User Part Number" "PARTNUM*"
			(at 0.1778 2.422881 270)
			(unlocked yes)
			(layer "Cmts.User")
			(hide yes)
			(effects
				(font
					(size 0.786892 0.583946)
					(thickness 0.000001)
				)
			)
		)
		(duplicate_pad_numbers_are_jumpers no)
		(fp_line
			(start -1.3208 1.0922)
			(end -2.5908 1.0922)
			(stroke
				(width 0.1)
				(type default)
			)
			(layer "F.SilkS")
		)
		(fp_line
			(start -1.397508 0.704088)
			(end -1.397508 -0.704088)
			(stroke
				(width 0.1)
				(type default)
			)
			(layer "F.SilkS")
		)
		(fp_line
			(start 1.397508 0.704088)
			(end -1.397508 0.704088)
			(stroke
				(width 0.1)
				(type default)
			)
			(layer "F.SilkS")
		)
		(fp_line
			(start -1.9558 0.4572)
			(end -1.9558 1.7272)
			(stroke
				(width 0.1)
				(type default)
			)
			(layer "F.SilkS")
		)
		(fp_line
			(start -1.397508 -0.704088)
			(end 1.397508 -0.704088)
			(stroke
				(width 0.1)
				(type default)
			)
			(layer "F.SilkS")
		)
		(fp_line
			(start 1.397508 -0.704088)
			(end 1.397508 0.704088)
			(stroke
				(width 0.1)
				(type default)
			)
			(layer "F.SilkS")
		)
		(fp_rect
			(start 1.905508 0.704088)
			(end 1.397508 -0.704088)
			(stroke
				(width 0)
				(type default)
			)
			(fill yes)
			(layer "F.SilkS")
		)
		(fp_rect
			(start 1.905508 0.958088)
			(end -1.651508 -0.958088)
			(stroke
				(width 0)
				(type default)
			)
			(fill no)
			(layer "F.CrtYd")
		)
		(fp_line
			(start -1.1938 1.2192)
			(end -2.4638 1.2192)
			(stroke
				(width 0.1)
				(type default)
			)
			(layer "F.Fab")
		)
		(fp_line
			(start -1.8288 0.5842)
			(end -1.8288 1.8542)
			(stroke
				(width 0.1)
				(type default)
			)
			(layer "F.Fab")
		)
		(fp_line
			(start -0.850138 0.450088)
			(end 0.850138 0.450088)
			(stroke
				(width 0.1)
				(type default)
			)
			(layer "F.Fab")
		)
		(fp_line
			(start 0.850138 0.450088)
			(end 0.850138 -0.450088)
			(stroke
				(width 0.1)
				(type default)
			)
			(layer "F.Fab")
		)
		(fp_line
			(start -0.850138 -0.450088)
			(end -0.850138 0.450088)
			(stroke
				(width 0.1)
				(type default)
			)
			(layer "F.Fab")
		)
		(fp_line
			(start 0.850138 -0.450088)
			(end -0.850138 -0.450088)
			(stroke
				(width 0.1)
				(type default)
			)
			(layer "F.Fab")
		)
		(fp_rect
			(start 0.850138 0.450088)
			(end 0.342138 -0.450088)
			(stroke
				(width 0)
				(type default)
			)
			(fill yes)
			(layer "F.Fab")
		)
		(fp_text user "A"
			(at -1.719326 -1.30302 0)
			(unlocked yes)
			(layer "F.SilkS")
			(effects
				(font
					(size 0.635 0.4064)
					(thickness 0.1524)
				)
			)
		)
		(fp_text user "C"
			(at 1.455674 -1.30302 0)
			(unlocked yes)
			(layer "F.SilkS")
			(effects
				(font
					(size 0.635 0.4064)
					(thickness 0.1524)
				)
			)
		)
		(fp_text user "A"
			(at -2.219706 -0.16002 0)
			(unlocked yes)
			(layer "F.Fab")
			(effects
				(font
					(size 0.7874 0.5842)
					(thickness 0.1524)
				)
			)
		)
		(fp_text user "C"
			(at 1.209294 -1.17602 0)
			(unlocked yes)
			(layer "F.Fab")
			(effects
				(font
					(size 0.7874 0.5842)
					(thickness 0.1524)
				)
			)
		)
		(pad "A" smd rect
			(at -0.749808 0 270)
			(size 0.7874 0.7874)
			(layers "F.Cu" "F.Mask" "F.Paste")
			(net "UNNAMED_14_OPTICAL_I139_A")
		)
		(pad "C" smd rect
			(at 0.749808 0 270)
			(size 0.7874 0.7874)
			(layers "F.Cu" "F.Mask" "F.Paste")
			(net "FPGA_USR_LED0")
		)
	)
	(footprint ""
		(layer "F.Cu")
		(at 101.0412 -64.2874 -90)
		(property "Reference" "R170"
			(at 2.6924 -0.85217 90)
			(unlocked yes)
			(layer "F.SilkS")
			(effects
				(font
					(size 0.7874 0.5842)
					(thickness 0.1524)
				)
			)
		)
		(property "Value" "VAL*"
			(at 0.02032 2.13233 270)
			(unlocked yes)
			(layer "F.Fab")
			(hide yes)
			(effects
				(font
					(size 0.7874 0.5842)
					(thickness 0.1524)
				)
			)
		)
		(property "Tolerance" "TOL*"
			(at 0.044704 3.05435 270)
			(unlocked yes)
			(layer "Cmts.User")
			(hide yes)
			(effects
				(font
					(size 0.7874 0.5842)
					(thickness 0.1524)
				)
			)
		)
		(property "User Part Number" "PARTNUM*"
			(at 0.02032 4.024884 270)
			(unlocked yes)
			(layer "Cmts.User")
			(hide yes)
			(effects
				(font
					(size 0.7874 0.5842)
					(thickness 0.1524)
				)
			)
		)
		(property "Device Type" "RESISTOR-G155-11002-01,10KOHM,A"
			(at 0.008382 1.210564 270)
			(unlocked yes)
			(layer "F.Fab")
			(hide yes)
			(effects
				(font
					(size 0.7874 0.5842)
					(thickness 0.1524)
				)
			)
		)
		(duplicate_pad_numbers_are_jumpers no)
		(fp_line
			(start -1.143 0.5588)
			(end 1.143 0.5588)
			(stroke
				(width 0.1)
				(type default)
			)
			(layer "F.SilkS")
		)
		(fp_line
			(start 1.143 0.5588)
			(end 1.143 -0.5588)
			(stroke
				(width 0.1)
				(type default)
			)
			(layer "F.SilkS")
		)
		(fp_line
			(start -1.143 -0.5588)
			(end -1.143 0.5588)
			(stroke
				(width 0.1)
				(type default)
			)
			(layer "F.SilkS")
		)
		(fp_line
			(start 1.143 -0.5588)
			(end -1.143 -0.5588)
			(stroke
				(width 0.1)
				(type default)
			)
			(layer "F.SilkS")
		)
		(fp_rect
			(start -1.143 0.5588)
			(end 1.143 -0.5588)
			(stroke
				(width 0)
				(type default)
			)
			(fill no)
			(layer "F.CrtYd")
		)
		(fp_line
			(start -0.508 0.3048)
			(end 0.508 0.3048)
			(stroke
				(width 0.1)
				(type default)
			)
			(layer "F.Fab")
		)
		(fp_line
			(start 0.508 0.3048)
			(end 0.508 -0.3048)
			(stroke
				(width 0.1)
				(type default)
			)
			(layer "F.Fab")
		)
		(fp_line
			(start -0.508 -0.3048)
			(end -0.508 0.3048)
			(stroke
				(width 0.1)
				(type default)
			)
			(layer "F.Fab")
		)
		(fp_line
			(start 0.508 -0.3048)
			(end -0.508 -0.3048)
			(stroke
				(width 0.1)
				(type default)
			)
			(layer "F.Fab")
		)
		(pad "1" smd rect
			(at -0.5334 0 270)
			(size 0.7112 0.6096)
			(layers "F.Cu" "F.Mask" "F.Paste")
			(net "XP3R3V_FPGA")
		)
		(pad "2" smd rect
			(at 0.5334 0 270)
			(size 0.7112 0.6096)
			(layers "F.Cu" "F.Mask" "F.Paste")
			(net "FPGA_IO_0")
		)
		(zone
			(layer "F.Cu")
			(hatch none 0.5)
			(connect_pads
				(clearance 0)
			)
			(min_thickness 0.25)
			(keepout
				(tracks allowed)
				(vias not_allowed)
				(pads allowed)
				(copperpour not_allowed)
				(footprints allowed)
			)
			(placement
				(enabled no)
				(sheetname "")
			)
			(fill
				(thermal_gap 0.5)
				(thermal_bridge_width 0.5)
				(island_removal_mode 0)
			)
			(polygon
				(pts
					(xy 100.7364 -64.3636) (xy 100.7364 -64.2112) (xy 101.346 -64.2112) (xy 101.346 -64.3636)
				)
			)
		)
	)
	(footprint ""
		(layer "F.Cu")
		(at 96.4438 -75.946 -90)
		(property "Reference" "C188"
			(at -19.177 27.82443 90)
			(unlocked yes)
			(layer "F.SilkS")
			(effects
				(font
					(size 0.7874 0.5842)
					(thickness 0.1524)
				)
			)
		)
		(property "Value" "VAL*"
			(at 0.0762 2.067306 270)
			(unlocked yes)
			(layer "F.Fab")
			(hide yes)
			(effects
				(font
					(size 0.7874 0.5842)
					(thickness 0.1524)
				)
			)
		)
		(property "Tolerance" "TOL*"
			(at 0.0762 3.032506 270)
			(unlocked yes)
			(layer "Cmts.User")
			(hide yes)
			(effects
				(font
					(size 0.7874 0.5842)
					(thickness 0.1524)
				)
			)
		)
		(property "User Part Number" "PARTNUM*"
			(at 0.1016 4.023106 270)
			(unlocked yes)
			(layer "Cmts.User")
			(hide yes)
			(effects
				(font
					(size 0.7874 0.5842)
					(thickness 0.1524)
				)
			)
		)
		(property "Device Type" "CAPACITOR-G105-0B104-EK,0.1UF,A"
			(at 0.0508 1.127506 270)
			(unlocked yes)
			(layer "F.Fab")
			(hide yes)
			(effects
				(font
					(size 0.7874 0.5842)
					(thickness 0.1524)
				)
			)
		)
		(duplicate_pad_numbers_are_jumpers no)
		(fp_line
			(start -1.143 0.5588)
			(end 1.143 0.5588)
			(stroke
				(width 0.1)
				(type default)
			)
			(layer "F.SilkS")
		)
		(fp_line
			(start 1.143 0.5588)
			(end 1.143 -0.5588)
			(stroke
				(width 0.1)
				(type default)
			)
			(layer "F.SilkS")
		)
		(fp_line
			(start -1.143 -0.5588)
			(end -1.143 0.5588)
			(stroke
				(width 0.1)
				(type default)
			)
			(layer "F.SilkS")
		)
		(fp_line
			(start 1.143 -0.5588)
			(end -1.143 -0.5588)
			(stroke
				(width 0.1)
				(type default)
			)
			(layer "F.SilkS")
		)
		(fp_rect
			(start -1.143 0.5588)
			(end 1.143 -0.5588)
			(stroke
				(width 0)
				(type default)
			)
			(fill no)
			(layer "F.CrtYd")
		)
		(fp_line
			(start -0.508 0.3048)
			(end 0.508 0.3048)
			(stroke
				(width 0.1)
				(type default)
			)
			(layer "F.Fab")
		)
		(fp_line
			(start 0.508 0.3048)
			(end 0.508 -0.3048)
			(stroke
				(width 0.1)
				(type default)
			)
			(layer "F.Fab")
		)
		(fp_line
			(start -0.508 -0.3048)
			(end -0.508 0.3048)
			(stroke
				(width 0.1)
				(type default)
			)
			(layer "F.Fab")
		)
		(fp_line
			(start 0.508 -0.3048)
			(end -0.508 -0.3048)
			(stroke
				(width 0.1)
				(type default)
			)
			(layer "F.Fab")
		)
		(pad "1" smd rect
			(at -0.5334 0 270)
			(size 0.7112 0.6096)
			(layers "F.Cu" "F.Mask" "F.Paste")
			(net "XP1R2V_VIN")
		)
		(pad "2" smd rect
			(at 0.5334 0 270)
			(size 0.7112 0.6096)
			(layers "F.Cu" "F.Mask" "F.Paste")
			(net "SG")
		)
		(zone
			(layer "F.Cu")
			(hatch none 0.5)
			(connect_pads
				(clearance 0)
			)
			(min_thickness 0.25)
			(keepout
				(tracks allowed)
				(vias not_allowed)
				(pads allowed)
				(copperpour not_allowed)
				(footprints allowed)
			)
			(placement
				(enabled no)
				(sheetname "")
			)
			(fill
				(thermal_gap 0.5)
				(thermal_bridge_width 0.5)
				(island_removal_mode 0)
			)
			(polygon
				(pts
					(xy 96.139 -76.0222) (xy 96.139 -75.8698) (xy 96.7486 -75.8698) (xy 96.7486 -76.0222)
				)
			)
		)
	)
	(footprint ""
		(layer "F.Cu")
		(at 11.557 -42.291 90)
		(property "Reference" "R499"
			(at 0 -1.16205 90)
			(unlocked yes)
			(layer "F.SilkS")
			(effects
				(font
					(size 0.635 0.4064)
					(thickness 0.1524)
				)
			)
		)
		(property "Value" "VAL*"
			(at 0.02032 2.13233 90)
			(unlocked yes)
			(layer "F.Fab")
			(hide yes)
			(effects
				(font
					(size 0.7874 0.5842)
					(thickness 0.1524)
				)
			)
		)
		(property "Tolerance" "TOL*"
			(at 0.044704 3.05435 90)
			(unlocked yes)
			(layer "Cmts.User")
			(hide yes)
			(effects
				(font
					(size 0.7874 0.5842)
					(thickness 0.1524)
				)
			)
		)
		(property "User Part Number" "PARTNUM*"
			(at 0.02032 4.024884 90)
			(unlocked yes)
			(layer "Cmts.User")
			(hide yes)
			(effects
				(font
					(size 0.7874 0.5842)
					(thickness 0.1524)
				)
			)
		)
		(property "Device Type" "RESISTOR-G155-11004-01,1MOHM,1%"
			(at 0.008382 1.210564 90)
			(unlocked yes)
			(layer "F.Fab")
			(hide yes)
			(effects
				(font
					(size 0.7874 0.5842)
					(thickness 0.1524)
				)
			)
		)
		(duplicate_pad_numbers_are_jumpers no)
		(fp_line
			(start 1.143 -0.5588)
			(end -1.143 -0.5588)
			(stroke
				(width 0.1)
				(type default)
			)
			(layer "F.SilkS")
		)
		(fp_line
			(start -1.143 -0.5588)
			(end -1.143 0.5588)
			(stroke
				(width 0.1)
				(type default)
			)
			(layer "F.SilkS")
		)
		(fp_line
			(start 1.143 0.5588)
			(end 1.143 -0.5588)
			(stroke
				(width 0.1)
				(type default)
			)
			(layer "F.SilkS")
		)
		(fp_line
			(start -1.143 0.5588)
			(end 1.143 0.5588)
			(stroke
				(width 0.1)
				(type default)
			)
			(layer "F.SilkS")
		)
		(fp_poly
			(pts
				(xy -1.143 0.5588) (xy 1.143 0.5588) (xy 1.143 -0.5588) (xy -1.143 -0.5588)
			)
			(stroke
				(width 0)
				(type default)
			)
			(fill no)
			(layer "F.CrtYd")
		)
		(fp_line
			(start 0.508 -0.3048)
			(end -0.508 -0.3048)
			(stroke
				(width 0.1)
				(type default)
			)
			(layer "F.Fab")
		)
		(fp_line
			(start -0.508 -0.3048)
			(end -0.508 0.3048)
			(stroke
				(width 0.1)
				(type default)
			)
			(layer "F.Fab")
		)
		(fp_line
			(start 0.508 0.3048)
			(end 0.508 -0.3048)
			(stroke
				(width 0.1)
				(type default)
			)
			(layer "F.Fab")
		)
		(fp_line
			(start -0.508 0.3048)
			(end 0.508 0.3048)
			(stroke
				(width 0.1)
				(type default)
			)
			(layer "F.Fab")
		)
		(pad "1" smd rect
			(at -0.5334 0 90)
			(size 0.7112 0.6096)
			(layers "F.Cu" "F.Mask" "F.Paste")
			(net "SG")
		)
		(pad "2" smd rect
			(at 0.5334 0 90)
			(size 0.7112 0.6096)
			(layers "F.Cu" "F.Mask" "F.Paste")
			(net "BF_SMA2_SIG_IO_CONN")
		)
		(zone
			(layer "F.Cu")
			(hatch none 0.5)
			(connect_pads
				(clearance 0)
			)
			(min_thickness 0.25)
			(keepout
				(tracks allowed)
				(vias not_allowed)
				(pads allowed)
				(copperpour not_allowed)
				(footprints allowed)
			)
			(placement
				(enabled no)
				(sheetname "")
			)
			(fill
				(thermal_gap 0.5)
				(thermal_bridge_width 0.5)
				(island_removal_mode 0)
			)
			(polygon
				(pts
					(xy 11.8618 -42.2148) (xy 11.8618 -42.3672) (xy 11.2522 -42.3672) (xy 11.2522 -42.2148)
				)
			)
		)
		(zone
			(layer "F.Cu")
			(hatch none 0.5)
			(connect_pads
				(clearance 0)
			)
			(min_thickness 0.25)
			(keepout
				(tracks not_allowed)
				(vias allowed)
				(pads allowed)
				(copperpour not_allowed)
				(footprints allowed)
			)
			(placement
				(enabled no)
				(sheetname "")
			)
			(fill
				(thermal_gap 0.5)
				(thermal_bridge_width 0.5)
				(island_removal_mode 0)
			)
			(polygon
				(pts
					(xy 11.8618 -42.2148) (xy 11.8618 -42.3672) (xy 11.2522 -42.3672) (xy 11.2522 -42.2148)
				)
			)
		)
	)
	(footprint ""
		(layer "F.Cu")
		(at 18.415 -81.28 180)
		(property "Reference" "R472"
			(at 0.635 -2.32537 0)
			(unlocked yes)
			(layer "F.SilkS")
			(effects
				(font
					(size 0.7874 0.5842)
					(thickness 0.1524)
				)
			)
		)
		(property "Value" "VAL*"
			(at 0.02032 2.13233 180)
			(unlocked yes)
			(layer "F.Fab")
			(hide yes)
			(effects
				(font
					(size 0.7874 0.5842)
					(thickness 0.1524)
				)
			)
		)
		(property "Tolerance" "TOL*"
			(at 0.044704 3.05435 180)
			(unlocked yes)
			(layer "Cmts.User")
			(hide yes)
			(effects
				(font
					(size 0.7874 0.5842)
					(thickness 0.1524)
				)
			)
		)
		(property "User Part Number" "PARTNUM*"
			(at 0.02032 4.024884 180)
			(unlocked yes)
			(layer "Cmts.User")
			(hide yes)
			(effects
				(font
					(size 0.7874 0.5842)
					(thickness 0.1524)
				)
			)
		)
		(property "Device Type" "RESISTOR-G155-100R0-J0,0OHM,-"
			(at 0.008382 1.210564 180)
			(unlocked yes)
			(layer "F.Fab")
			(hide yes)
			(effects
				(font
					(size 0.7874 0.5842)
					(thickness 0.1524)
				)
			)
		)
		(duplicate_pad_numbers_are_jumpers no)
		(fp_line
			(start 1.143 0.5588)
			(end 1.143 -0.5588)
			(stroke
				(width 0.1)
				(type default)
			)
			(layer "F.SilkS")
		)
		(fp_line
			(start 1.143 -0.5588)
			(end -1.143 -0.5588)
			(stroke
				(width 0.1)
				(type default)
			)
			(layer "F.SilkS")
		)
		(fp_line
			(start -1.143 0.5588)
			(end 1.143 0.5588)
			(stroke
				(width 0.1)
				(type default)
			)
			(layer "F.SilkS")
		)
		(fp_line
			(start -1.143 -0.5588)
			(end -1.143 0.5588)
			(stroke
				(width 0.1)
				(type default)
			)
			(layer "F.SilkS")
		)
		(fp_poly
			(pts
				(xy -1.143 0.5588) (xy 1.143 0.5588) (xy 1.143 -0.5588) (xy -1.143 -0.5588)
			)
			(stroke
				(width 0)
				(type default)
			)
			(fill no)
			(layer "F.CrtYd")
		)
		(fp_line
			(start 0.508 0.3048)
			(end 0.508 -0.3048)
			(stroke
				(width 0.1)
				(type default)
			)
			(layer "F.Fab")
		)
		(fp_line
			(start 0.508 -0.3048)
			(end -0.508 -0.3048)
			(stroke
				(width 0.1)
				(type default)
			)
			(layer "F.Fab")
		)
		(fp_line
			(start -0.508 0.3048)
			(end 0.508 0.3048)
			(stroke
				(width 0.1)
				(type default)
			)
			(layer "F.Fab")
		)
		(fp_line
			(start -0.508 -0.3048)
			(end -0.508 0.3048)
			(stroke
				(width 0.1)
				(type default)
			)
			(layer "F.Fab")
		)
		(pad "1" smd rect
			(at -0.5334 0 180)
			(size 0.7112 0.6096)
			(layers "F.Cu" "F.Mask" "F.Paste")
			(net "R_FT4232_I2C_SDA_OUT")
		)
		(pad "2" smd rect
			(at 0.5334 0 180)
			(size 0.7112 0.6096)
			(layers "F.Cu" "F.Mask" "F.Paste")
			(net "FT4232_I2C_SDA")
		)
		(zone
			(layer "F.Cu")
			(hatch none 0.5)
			(connect_pads
				(clearance 0)
			)
			(min_thickness 0.25)
			(keepout
				(tracks not_allowed)
				(vias allowed)
				(pads allowed)
				(copperpour not_allowed)
				(footprints allowed)
			)
			(placement
				(enabled no)
				(sheetname "")
			)
			(fill
				(thermal_gap 0.5)
				(thermal_bridge_width 0.5)
				(island_removal_mode 0)
			)
			(polygon
				(pts
					(xy 18.4912 -81.5848) (xy 18.3388 -81.5848) (xy 18.3388 -80.9752) (xy 18.4912 -80.9752)
				)
			)
		)
		(zone
			(layer "F.Cu")
			(hatch none 0.5)
			(connect_pads
				(clearance 0)
			)
			(min_thickness 0.25)
			(keepout
				(tracks allowed)
				(vias not_allowed)
				(pads allowed)
				(copperpour not_allowed)
				(footprints allowed)
			)
			(placement
				(enabled no)
				(sheetname "")
			)
			(fill
				(thermal_gap 0.5)
				(thermal_bridge_width 0.5)
				(island_removal_mode 0)
			)
			(polygon
				(pts
					(xy 18.4912 -81.5848) (xy 18.3388 -81.5848) (xy 18.3388 -80.9752) (xy 18.4912 -80.9752)
				)
			)
		)
	)
)
